(kicad_pcb
	(version 20260206)
	(generator "pcbnew")
	(generator_version "10.0")
	(general
		(thickness 1.6)
		(legacy_teardrops no)
	)
	(paper "A4")
	(title_block
		(title "baseboard — 13948-1b.1110WZS1818.brd")
		(comment 1 "Honey Badger (Wiwynn) / footprints 1969-1977 of 2523")
	)
	(layers
		(0 "F.Cu" signal "TOP")
		(4 "In1.Cu" signal "L2GND")
		(6 "In2.Cu" signal "L3")
		(8 "In3.Cu" signal "L4VCC")
		(10 "In4.Cu" signal "L5VCC")
		(12 "In5.Cu" signal "L6")
		(14 "In6.Cu" signal "L7GND")
		(2 "B.Cu" signal "BOTTOM")
		(9 "F.Adhes" user "F.Adhesive")
		(11 "B.Adhes" user "B.Adhesive")
		(13 "F.Paste" user "Package Geometry/Pastemask Top")
		(15 "B.Paste" user "Package Geometry/Pastemask Bottom")
		(5 "F.SilkS" user "Ref Des/Silkscreen Top")
		(7 "B.SilkS" user "Ref Des/Silkscreen Bottom")
		(1 "F.Mask" user "Board Geometry/Soldermask Top")
		(3 "B.Mask" user "Board Geometry/Soldermask Bottom")
		(17 "Dwgs.User" user "User.Drawings")
		(19 "Cmts.User" user "User.Comments")
		(21 "Eco1.User" user "User.Eco1")
		(23 "Eco2.User" user "User.Eco2")
		(25 "Edge.Cuts" user "Board Geometry/Outline")
		(27 "Margin" user)
		(31 "F.CrtYd" user "Package Geometry/Place Bound Top")
		(29 "B.CrtYd" user "Package Geometry/Place Bound Bottom")
		(35 "F.Fab" user "Ref Des/Assembly Top")
		(33 "B.Fab" user "Ref Des/Assembly Bottom")
	)
	(footprint ""
		(layer "B.Cu")
		(at 300.863 -185.547)
		(property "Reference" "TP145"
			(at 0 0 0)
			(layer "B.SilkS")
			(hide yes)
			(effects
				(font
					(size 1.27 1.27)
				)
				(justify mirror)
			)
		)
		(property "Value" "TPAD28"
			(at -0.0127 -1.8034 0)
			(unlocked yes)
			(layer "B.Fab")
			(hide yes)
			(effects
				(font
					(size 1.016 1.016)
					(thickness 0.1524)
				)
				(justify mirror)
			)
		)
		(property "Device Type" "TPAD28"
			(at -0.0127 -3.3274 0)
			(unlocked yes)
			(layer "B.Fab")
			(hide yes)
			(effects
				(font
					(size 1.016 1.016)
					(thickness 0.1524)
				)
				(justify mirror)
			)
		)
		(duplicate_pad_numbers_are_jumpers no)
		(fp_poly
			(pts
				(arc
					(start 0.3556 0)
					(mid -0.3556 0)
					(end 0.3556 0)
				)
			)
			(stroke
				(width 0)
				(type default)
			)
			(fill no)
			(layer "B.CrtYd")
		)
		(fp_poly
			(pts
				(arc
					(start 0.6096 0)
					(mid -0.6096 0)
					(end 0.6096 0)
				)
			)
			(stroke
				(width 0)
				(type default)
			)
			(fill no)
			(layer "B.Fab")
		)
		(pad "1" smd circle
			(at 0 0 180)
			(size 0.7112 0.7112)
			(layers "B.Cu" "B.Mask" "B.Paste")
			(net "TP_BMC0_TACH8")
		)
	)
	(footprint ""
		(layer "B.Cu")
		(at 21.739352 -216.726008 -90)
		(property "Reference" "SC634"
			(at 0 0 90)
			(layer "B.SilkS")
			(hide yes)
			(effects
				(font
					(size 1.27 1.27)
				)
				(justify mirror)
			)
		)
		(property "Value" "SCD1U16V2KX-3GP"
			(at -1.1811 -2.7051 270)
			(unlocked yes)
			(layer "B.Fab")
			(hide yes)
			(effects
				(font
					(size 1.016 1.016)
					(thickness 0.1524)
				)
				(justify mirror)
			)
		)
		(property "Device Type" "C402H22"
			(at -1.1811 -4.2291 270)
			(unlocked yes)
			(layer "B.Fab")
			(hide yes)
			(effects
				(font
					(size 1.016 1.016)
					(thickness 0.1524)
				)
				(justify mirror)
			)
		)
		(duplicate_pad_numbers_are_jumpers no)
		(fp_rect
			(start 0.4318 0.9525)
			(end -0.4318 -0.9525)
			(stroke
				(width 0)
				(type default)
			)
			(fill no)
			(layer "B.CrtYd")
		)
		(fp_rect
			(start 0.4318 0.9525)
			(end -0.4318 -0.9525)
			(stroke
				(width 0)
				(type default)
			)
			(fill no)
			(layer "B.Fab")
		)
		(pad "1" smd custom
			(at 0 -0.4445 90)
			(size 0.1524 0.1524)
			(layers "B.Cu" "B.Mask" "B.Paste")
			(net "P3V3_STBY")
			(options
				(clearance outline)
				(anchor circle)
			)
			(primitives
				(gr_poly
					(pts
						(arc
							(start 0.3048 0.2032)
							(mid 0.275042 0.275042)
							(end 0.2032 0.3048)
						)
						(arc
							(start -0.2032 0.3048)
							(mid -0.275042 0.275042)
							(end -0.3048 0.2032)
						)
						(arc
							(start -0.3048 -0.2032)
							(mid -0.275042 -0.275042)
							(end -0.2032 -0.3048)
						)
						(arc
							(start 0.2032 -0.3048)
							(mid 0.275042 -0.275042)
							(end 0.3048 -0.2032)
						)
					)
					(width 0)
					(fill yes)
				)
			)
		)
		(pad "2" smd custom
			(at 0 0.4445 90)
			(size 0.1524 0.1524)
			(layers "B.Cu" "B.Mask" "B.Paste")
			(net "GND")
			(options
				(clearance outline)
				(anchor circle)
			)
			(primitives
				(gr_poly
					(pts
						(arc
							(start 0.3048 0.2032)
							(mid 0.275042 0.275042)
							(end 0.2032 0.3048)
						)
						(arc
							(start -0.2032 0.3048)
							(mid -0.275042 0.275042)
							(end -0.3048 0.2032)
						)
						(arc
							(start -0.3048 -0.2032)
							(mid -0.275042 -0.275042)
							(end -0.2032 -0.3048)
						)
						(arc
							(start 0.2032 -0.3048)
							(mid 0.275042 -0.275042)
							(end 0.3048 -0.2032)
						)
					)
					(width 0)
					(fill yes)
				)
			)
		)
	)
	(footprint ""
		(layer "B.Cu")
		(at 30.811216 -203.38288 -90)
		(property "Reference" "C320"
			(at 0 0 90)
			(layer "B.SilkS")
			(hide yes)
			(effects
				(font
					(size 1.27 1.27)
				)
				(justify mirror)
			)
		)
		(property "Value" "SC1U10V2KX-4-GP"
			(at -1.1811 -2.7051 270)
			(unlocked yes)
			(layer "B.Fab")
			(hide yes)
			(effects
				(font
					(size 1.016 1.016)
					(thickness 0.1524)
				)
				(justify mirror)
			)
		)
		(property "Device Type" "C402H22"
			(at -1.1811 -4.2291 270)
			(unlocked yes)
			(layer "B.Fab")
			(hide yes)
			(effects
				(font
					(size 1.016 1.016)
					(thickness 0.1524)
				)
				(justify mirror)
			)
		)
		(duplicate_pad_numbers_are_jumpers no)
		(fp_rect
			(start 0.4318 0.9525)
			(end -0.4318 -0.9525)
			(stroke
				(width 0)
				(type default)
			)
			(fill no)
			(layer "B.CrtYd")
		)
		(fp_rect
			(start 0.4318 0.9525)
			(end -0.4318 -0.9525)
			(stroke
				(width 0)
				(type default)
			)
			(fill no)
			(layer "B.Fab")
		)
		(pad "1" smd custom
			(at 0 -0.4445 90)
			(size 0.1524 0.1524)
			(layers "B.Cu" "B.Mask" "B.Paste")
			(net "P3V3_STBY")
			(options
				(clearance outline)
				(anchor circle)
			)
			(primitives
				(gr_poly
					(pts
						(arc
							(start 0.3048 0.2032)
							(mid 0.275042 0.275042)
							(end 0.2032 0.3048)
						)
						(arc
							(start -0.2032 0.3048)
							(mid -0.275042 0.275042)
							(end -0.3048 0.2032)
						)
						(arc
							(start -0.3048 -0.2032)
							(mid -0.275042 -0.275042)
							(end -0.2032 -0.3048)
						)
						(arc
							(start 0.2032 -0.3048)
							(mid 0.275042 -0.275042)
							(end 0.3048 -0.2032)
						)
					)
					(width 0)
					(fill yes)
				)
			)
		)
		(pad "2" smd custom
			(at 0 0.4445 90)
			(size 0.1524 0.1524)
			(layers "B.Cu" "B.Mask" "B.Paste")
			(net "GND")
			(options
				(clearance outline)
				(anchor circle)
			)
			(primitives
				(gr_poly
					(pts
						(arc
							(start 0.3048 0.2032)
							(mid 0.275042 0.275042)
							(end 0.2032 0.3048)
						)
						(arc
							(start -0.2032 0.3048)
							(mid -0.275042 0.275042)
							(end -0.3048 0.2032)
						)
						(arc
							(start -0.3048 -0.2032)
							(mid -0.275042 -0.275042)
							(end -0.2032 -0.3048)
						)
						(arc
							(start 0.2032 -0.3048)
							(mid 0.275042 -0.275042)
							(end 0.3048 -0.2032)
						)
					)
					(width 0)
					(fill yes)
				)
			)
		)
	)
	(footprint ""
		(layer "B.Cu")
		(at 110.657386 -56.734456)
		(property "Reference" "STP158"
			(at 0 0 0)
			(layer "B.SilkS")
			(hide yes)
			(effects
				(font
					(size 1.27 1.27)
				)
				(justify mirror)
			)
		)
		(property "Value" "TPAD28"
			(at -0.0127 -1.8034 0)
			(unlocked yes)
			(layer "B.Fab")
			(hide yes)
			(effects
				(font
					(size 1.016 1.016)
					(thickness 0.1524)
				)
				(justify mirror)
			)
		)
		(property "Device Type" "TPAD28"
			(at -0.0127 -3.3274 0)
			(unlocked yes)
			(layer "B.Fab")
			(hide yes)
			(effects
				(font
					(size 1.016 1.016)
					(thickness 0.1524)
				)
				(justify mirror)
			)
		)
		(duplicate_pad_numbers_are_jumpers no)
		(fp_poly
			(pts
				(arc
					(start 0.3556 0)
					(mid -0.3556 0)
					(end 0.3556 0)
				)
			)
			(stroke
				(width 0)
				(type default)
			)
			(fill no)
			(layer "B.CrtYd")
		)
		(fp_poly
			(pts
				(arc
					(start 0.6096 0)
					(mid -0.6096 0)
					(end 0.6096 0)
				)
			)
			(stroke
				(width 0)
				(type default)
			)
			(fill no)
			(layer "B.Fab")
		)
		(pad "1" smd circle
			(at 0 0 180)
			(size 0.7112 0.7112)
			(layers "B.Cu" "B.Mask" "B.Paste")
			(net "XM_WP")
		)
	)
	(footprint ""
		(layer "B.Cu")
		(at 274.193 -173.609 90)
		(property "Reference" "R332"
			(at 0 0 90)
			(layer "B.SilkS")
			(hide yes)
			(effects
				(font
					(size 1.27 1.27)
				)
				(justify mirror)
			)
		)
		(property "Value" "0R2J-2-GP"
			(at -0.064008 -3.993896 90)
			(unlocked yes)
			(layer "B.Fab")
			(hide yes)
			(effects
				(font
					(size 1.016 1.016)
					(thickness 0.1524)
				)
				(justify mirror)
			)
		)
		(property "Device Type" "R402H16"
			(at -0.064008 -5.517896 90)
			(unlocked yes)
			(layer "B.Fab")
			(hide yes)
			(effects
				(font
					(size 1.016 1.016)
					(thickness 0.1524)
				)
				(justify mirror)
			)
		)
		(duplicate_pad_numbers_are_jumpers no)
		(fp_line
			(start 0.508 -0.9398)
			(end 0.508 0.9398)
			(stroke
				(width 0.1524)
				(type default)
			)
			(layer "B.SilkS")
		)
		(fp_line
			(start -0.508 -0.9398)
			(end 0.508 -0.9398)
			(stroke
				(width 0.1524)
				(type default)
			)
			(layer "B.SilkS")
		)
		(fp_rect
			(start 0.508 0.9398)
			(end -0.508 -0.9398)
			(stroke
				(width 0)
				(type default)
			)
			(fill no)
			(layer "B.CrtYd")
		)
		(fp_rect
			(start 0.508 0.9398)
			(end -0.508 -0.9398)
			(stroke
				(width 0)
				(type default)
			)
			(fill no)
			(layer "B.Fab")
		)
		(pad "1" smd custom
			(at 0 -0.4445 270)
			(size 0.1397 0.1397)
			(layers "B.Cu" "B.Mask" "B.Paste")
			(net "SAS_SEB_PEER_PRSNT_BMC")
			(options
				(clearance outline)
				(anchor circle)
			)
			(primitives
				(gr_poly
					(pts
						(arc
							(start -0.1778 0.2794)
							(mid -0.249642 0.249642)
							(end -0.2794 0.1778)
						)
						(arc
							(start -0.2794 -0.1778)
							(mid -0.249642 -0.249642)
							(end -0.1778 -0.2794)
						)
						(arc
							(start 0.1778 -0.2794)
							(mid 0.249642 -0.249642)
							(end 0.2794 -0.1778)
						)
						(arc
							(start 0.2794 0.1778)
							(mid 0.249642 0.249642)
							(end 0.1778 0.2794)
						)
					)
					(width 0)
					(fill yes)
				)
			)
		)
		(pad "2" smd custom
			(at 0 0.4445 270)
			(size 0.1397 0.1397)
			(layers "B.Cu" "B.Mask" "B.Paste")
			(net "MB0_PRESNET#")
			(options
				(clearance outline)
				(anchor circle)
			)
			(primitives
				(gr_poly
					(pts
						(arc
							(start -0.1778 0.2794)
							(mid -0.249642 0.249642)
							(end -0.2794 0.1778)
						)
						(arc
							(start -0.2794 -0.1778)
							(mid -0.249642 -0.249642)
							(end -0.1778 -0.2794)
						)
						(arc
							(start 0.1778 -0.2794)
							(mid 0.249642 -0.249642)
							(end 0.2794 -0.1778)
						)
						(arc
							(start 0.2794 0.1778)
							(mid 0.249642 0.249642)
							(end 0.1778 0.2794)
						)
					)
					(width 0)
					(fill yes)
				)
			)
		)
	)
	(footprint ""
		(layer "B.Cu")
		(at 103.432356 -50.3047 180)
		(property "Reference" "SC1038"
			(at 0 0 0)
			(layer "B.SilkS")
			(hide yes)
			(effects
				(font
					(size 1.27 1.27)
				)
				(justify mirror)
			)
		)
		(property "Value" "SCD1U16V2KX-3GP"
			(at -1.1811 -2.7051 180)
			(unlocked yes)
			(layer "B.Fab")
			(hide yes)
			(effects
				(font
					(size 1.016 1.016)
					(thickness 0.1524)
				)
				(justify mirror)
			)
		)
		(property "Device Type" "C402H22"
			(at -1.1811 -4.2291 180)
			(unlocked yes)
			(layer "B.Fab")
			(hide yes)
			(effects
				(font
					(size 1.016 1.016)
					(thickness 0.1524)
				)
				(justify mirror)
			)
		)
		(duplicate_pad_numbers_are_jumpers no)
		(fp_rect
			(start 0.4318 0.9525)
			(end -0.4318 -0.9525)
			(stroke
				(width 0)
				(type default)
			)
			(fill no)
			(layer "B.CrtYd")
		)
		(fp_rect
			(start 0.4318 0.9525)
			(end -0.4318 -0.9525)
			(stroke
				(width 0)
				(type default)
			)
			(fill no)
			(layer "B.Fab")
		)
		(pad "1" smd custom
			(at 0 -0.4445)
			(size 0.1524 0.1524)
			(layers "B.Cu" "B.Mask" "B.Paste")
			(net "P0V955_C")
			(options
				(clearance outline)
				(anchor circle)
			)
			(primitives
				(gr_poly
					(pts
						(arc
							(start 0.3048 0.2032)
							(mid 0.275042 0.275042)
							(end 0.2032 0.3048)
						)
						(arc
							(start -0.2032 0.3048)
							(mid -0.275042 0.275042)
							(end -0.3048 0.2032)
						)
						(arc
							(start -0.3048 -0.2032)
							(mid -0.275042 -0.275042)
							(end -0.2032 -0.3048)
						)
						(arc
							(start 0.2032 -0.3048)
							(mid 0.275042 -0.275042)
							(end 0.3048 -0.2032)
						)
					)
					(width 0)
					(fill yes)
				)
			)
		)
		(pad "2" smd custom
			(at 0 0.4445)
			(size 0.1524 0.1524)
			(layers "B.Cu" "B.Mask" "B.Paste")
			(net "GND")
			(options
				(clearance outline)
				(anchor circle)
			)
			(primitives
				(gr_poly
					(pts
						(arc
							(start 0.3048 0.2032)
							(mid 0.275042 0.275042)
							(end 0.2032 0.3048)
						)
						(arc
							(start -0.2032 0.3048)
							(mid -0.275042 0.275042)
							(end -0.3048 0.2032)
						)
						(arc
							(start -0.3048 -0.2032)
							(mid -0.275042 -0.275042)
							(end -0.2032 -0.3048)
						)
						(arc
							(start 0.2032 -0.3048)
							(mid 0.275042 -0.275042)
							(end 0.3048 -0.2032)
						)
					)
					(width 0)
					(fill yes)
				)
			)
		)
	)
	(footprint ""
		(layer "B.Cu")
		(at 109.97057 -91.27998 -90)
		(property "Reference" "SC1250"
			(at 0 0 90)
			(layer "B.SilkS")
			(hide yes)
			(effects
				(font
					(size 1.27 1.27)
				)
				(justify mirror)
			)
		)
		(property "Value" "SCD1U6D3V1KX-GP"
			(at 2.8321 -1.7399 270)
			(unlocked yes)
			(layer "B.Fab")
			(hide yes)
			(effects
				(font
					(size 1.016 1.016)
					(thickness 0.1524)
				)
				(justify mirror)
			)
		)
		(property "Device Type" "C0201H13"
			(at 2.8321 -3.2639 270)
			(unlocked yes)
			(layer "B.Fab")
			(hide yes)
			(effects
				(font
					(size 1.016 1.016)
					(thickness 0.1524)
				)
				(justify mirror)
			)
		)
		(duplicate_pad_numbers_are_jumpers no)
		(fp_rect
			(start 0.2794 0.6477)
			(end -0.2794 -0.6477)
			(stroke
				(width 0)
				(type default)
			)
			(fill no)
			(layer "B.CrtYd")
		)
		(fp_rect
			(start 0.2794 0.6477)
			(end -0.2794 -0.6477)
			(stroke
				(width 0)
				(type default)
			)
			(fill no)
			(layer "B.Fab")
		)
		(pad "1" smd custom
			(at 0 -0.2794 90)
			(size 0.0762 0.0762)
			(layers "B.Cu" "B.Mask" "B.Paste")
			(net "P0V9_E")
			(options
				(clearance outline)
				(anchor circle)
			)
			(primitives
				(gr_poly
					(pts
						(arc
							(start 0.1524 0.127)
							(mid 0.137521 0.162921)
							(end 0.1016 0.1778)
						)
						(arc
							(start -0.1016 0.1778)
							(mid -0.137521 0.162921)
							(end -0.1524 0.127)
						)
						(arc
							(start -0.1524 -0.127)
							(mid -0.137521 -0.162921)
							(end -0.1016 -0.1778)
						)
						(arc
							(start 0.1016 -0.1778)
							(mid 0.137521 -0.162921)
							(end 0.1524 -0.127)
						)
					)
					(width 0)
					(fill yes)
				)
			)
		)
		(pad "2" smd custom
			(at 0 0.2794 90)
			(size 0.0762 0.0762)
			(layers "B.Cu" "B.Mask" "B.Paste")
			(net "GND")
			(options
				(clearance outline)
				(anchor circle)
			)
			(primitives
				(gr_poly
					(pts
						(arc
							(start 0.1524 0.127)
							(mid 0.137521 0.162921)
							(end 0.1016 0.1778)
						)
						(arc
							(start -0.1016 0.1778)
							(mid -0.137521 0.162921)
							(end -0.1524 0.127)
						)
						(arc
							(start -0.1524 -0.127)
							(mid -0.137521 -0.162921)
							(end -0.1016 -0.1778)
						)
						(arc
							(start 0.1016 -0.1778)
							(mid 0.137521 -0.162921)
							(end 0.1524 -0.127)
						)
					)
					(width 0)
					(fill yes)
				)
			)
		)
	)
	(footprint ""
		(layer "B.Cu")
		(at 116.059966 -36.322)
		(property "Reference" "STP135"
			(at 0 0 0)
			(layer "B.SilkS")
			(hide yes)
			(effects
				(font
					(size 1.27 1.27)
				)
				(justify mirror)
			)
		)
		(property "Value" "TPAD28"
			(at -0.0127 -1.8034 0)
			(unlocked yes)
			(layer "B.Fab")
			(hide yes)
			(effects
				(font
					(size 1.016 1.016)
					(thickness 0.1524)
				)
				(justify mirror)
			)
		)
		(property "Device Type" "TPAD28"
			(at -0.0127 -3.3274 0)
			(unlocked yes)
			(layer "B.Fab")
			(hide yes)
			(effects
				(font
					(size 1.016 1.016)
					(thickness 0.1524)
				)
				(justify mirror)
			)
		)
		(duplicate_pad_numbers_are_jumpers no)
		(fp_poly
			(pts
				(arc
					(start 0.3556 0)
					(mid -0.3556 0)
					(end 0.3556 0)
				)
			)
			(stroke
				(width 0)
				(type default)
			)
			(fill no)
			(layer "B.CrtYd")
		)
		(fp_poly
			(pts
				(arc
					(start 0.6096 0)
					(mid -0.6096 0)
					(end 0.6096 0)
				)
			)
			(stroke
				(width 0)
				(type default)
			)
			(fill no)
			(layer "B.Fab")
		)
		(pad "1" smd circle
			(at 0 0 180)
			(size 0.7112 0.7112)
			(layers "B.Cu" "B.Mask" "B.Paste")
			(net "IOC_GPIO_17")
		)
	)
	(footprint ""
		(layer "B.Cu")
		(at 15.833344 -176.149762 90)
		(property "Reference" "SC1115"
			(at 0 0 90)
			(layer "B.SilkS")
			(hide yes)
			(effects
				(font
					(size 1.27 1.27)
				)
				(justify mirror)
			)
		)
		(property "Value" "SCD1U16V2KX-3GP"
			(at -1.1811 -2.7051 90)
			(unlocked yes)
			(layer "B.Fab")
			(hide yes)
			(effects
				(font
					(size 1.016 1.016)
					(thickness 0.1524)
				)
				(justify mirror)
			)
		)
		(property "Device Type" "C402H22"
			(at -1.1811 -4.2291 90)
			(unlocked yes)
			(layer "B.Fab")
			(hide yes)
			(effects
				(font
					(size 1.016 1.016)
					(thickness 0.1524)
				)
				(justify mirror)
			)
		)
		(duplicate_pad_numbers_are_jumpers no)
		(fp_rect
			(start 0.4318 0.9525)
			(end -0.4318 -0.9525)
			(stroke
				(width 0)
				(type default)
			)
			(fill no)
			(layer "B.CrtYd")
		)
		(fp_rect
			(start 0.4318 0.9525)
			(end -0.4318 -0.9525)
			(stroke
				(width 0)
				(type default)
			)
			(fill no)
			(layer "B.Fab")
		)
		(pad "1" smd custom
			(at 0 -0.4445 270)
			(size 0.1524 0.1524)
			(layers "B.Cu" "B.Mask" "B.Paste")
			(net "P3V3_STBY")
			(options
				(clearance outline)
				(anchor circle)
			)
			(primitives
				(gr_poly
					(pts
						(arc
							(start 0.3048 0.2032)
							(mid 0.275042 0.275042)
							(end 0.2032 0.3048)
						)
						(arc
							(start -0.2032 0.3048)
							(mid -0.275042 0.275042)
							(end -0.3048 0.2032)
						)
						(arc
							(start -0.3048 -0.2032)
							(mid -0.275042 -0.275042)
							(end -0.2032 -0.3048)
						)
						(arc
							(start 0.2032 -0.3048)
							(mid 0.275042 -0.275042)
							(end 0.3048 -0.2032)
						)
					)
					(width 0)
					(fill yes)
				)
			)
		)
		(pad "2" smd custom
			(at 0 0.4445 270)
			(size 0.1524 0.1524)
			(layers "B.Cu" "B.Mask" "B.Paste")
			(net "GND")
			(options
				(clearance outline)
				(anchor circle)
			)
			(primitives
				(gr_poly
					(pts
						(arc
							(start 0.3048 0.2032)
							(mid 0.275042 0.275042)
							(end 0.2032 0.3048)
						)
						(arc
							(start -0.2032 0.3048)
							(mid -0.275042 0.275042)
							(end -0.3048 0.2032)
						)
						(arc
							(start -0.3048 -0.2032)
							(mid -0.275042 -0.275042)
							(end -0.2032 -0.3048)
						)
						(arc
							(start 0.2032 -0.3048)
							(mid 0.275042 -0.275042)
							(end 0.3048 -0.2032)
						)
					)
					(width 0)
					(fill yes)
				)
			)
		)
	)
)
